FILE_TYPE = MULTI_PHYS_TABLE;
PART 'SNLABEL_A'
CLASS='MECHANICAL'
{=================================================================================================================================================}
:PACK_TYPE | MATERIAL | PART_NUMBER     = EnvComp | PART_NUMBER  | JEDEC_TYPE    | DESCRIPTION | HEIGHT     | COMPONENT_TYPE | LEAD_LENGTH |  LPID  | SPEED_URL | Status |RPL| AML | Bus_Unit | Days ;
{=================================================================================================================================================}
'LABEL'    | 'EMPTY'  | 'N_A'(!)        = '' | 'N_A'        | 'SNLABELA'    | 'SNLABEL'   | '0.001 IN' | 'PSEUDO'       | ''          | '' | 'http://speed.intel.com:8081/speed/module/pdm/item/pdm_item_detail_direct.asp?item_cde=N_A&item_rev=01&url_param=unused' | '???' | '???' | '???' | '' | '???' 
END_PART
END.
